# S9S_MB_2U (Grand Teton) — schematic netlist excerpt (pin names and nets, part order shuffled) for the footprints in the layout excerpt that follows; sources: Cadence DE-HDL packaged netlist, KiCad conversion of 03242023_DA0F0TMBIJ0_F0T_Motherboard_J_brd_V01_OCP.brd

R569  Q_RES  4.7K 1% EMPTY  pkg 0402LF  page 206 : A = P3V3 ; B = PD_DB2000_SMB_SA0
R59  Q_RES  0 5% CHIP  pkg 0402LF  page 45 : A = SVID_CLK1_CPU1 ; B = SVID_CLK1_CPU1_R

(kicad_pcb
	(version 20260206)
	(generator "pcbnew")
	(generator_version "10.0")
	(general
		(thickness 1.6)
		(legacy_teardrops no)
	)
	(paper "A4")
	(title_block
		(title "03242023_DA0F0TMBIJ0_F0T_Motherboard_J_brd_V01_OCP.brd")
		(comment 1 "Grand Teton / footprints 5595-5596 of 6105")
	)
	(layers
		(0 "F.Cu" signal "TOP")
		(4 "In1.Cu" signal "GND")
		(6 "In2.Cu" signal "IN1")
		(8 "In3.Cu" signal "GND1")
		(10 "In4.Cu" signal "IN2")
		(12 "In5.Cu" signal "GND2")
		(14 "In6.Cu" signal "IN3")
		(16 "In7.Cu" signal "GND3")
		(18 "In8.Cu" signal "VCC")
		(20 "In9.Cu" signal "VCC1")
		(22 "In10.Cu" signal "GND4")
		(24 "In11.Cu" signal "IN4")
		(26 "In12.Cu" signal "GND5")
		(28 "In13.Cu" signal "IN5")
		(30 "In14.Cu" signal "GND6")
		(32 "In15.Cu" signal "IN6")
		(34 "In16.Cu" signal "GND7")
		(2 "B.Cu" signal "BOTTOM")
		(9 "F.Adhes" user "F.Adhesive")
		(11 "B.Adhes" user "B.Adhesive")
		(13 "F.Paste" user "Package Geometry/Pastemask Top")
		(15 "B.Paste" user "Package Geometry/Pastemask Bottom")
		(5 "F.SilkS" user "Ref Des/Silkscreen Top")
		(7 "B.SilkS" user "Ref Des/Silkscreen Bottom")
		(1 "F.Mask" user "Board Geometry/Soldermask Top")
		(3 "B.Mask" user "Board Geometry/Soldermask Bottom")
		(17 "Dwgs.User" user "User.Drawings")
		(19 "Cmts.User" user "User.Comments")
		(21 "Eco1.User" user "User.Eco1")
		(23 "Eco2.User" user "User.Eco2")
		(25 "Edge.Cuts" user "Board Geometry/Outline")
		(27 "Margin" user)
		(31 "F.CrtYd" user "Package Geometry/Place Bound Top")
		(29 "B.CrtYd" user "Package Geometry/Place Bound Bottom")
		(35 "F.Fab" user "Ref Des/Assembly Top")
		(33 "B.Fab" user "Ref Des/Assembly Bottom")
	)
	(footprint ""
		(layer "B.Cu")
		(at 245.96217 -128.330452 90)
		(property "Reference" "R569"
			(at 0 0 90)
			(layer "B.SilkS")
			(hide yes)
			(effects
				(font
					(size 1.27 1.27)
				)
				(justify mirror)
			)
		)
		(property "Value" ""
			(at 0 0 90)
			(layer "B.Fab")
			(effects
				(font
					(size 1.27 1.27)
				)
				(justify mirror)
			)
		)
		(duplicate_pad_numbers_are_jumpers no)
		(fp_line
			(start 0.7874 -0.4064)
			(end -0.7874 -0.4064)
			(stroke
				(width 0.1524)
				(type default)
			)
			(layer "B.SilkS")
		)
		(fp_line
			(start -0.7874 -0.4064)
			(end -0.7874 0.4064)
			(stroke
				(width 0.1524)
				(type default)
			)
			(layer "B.SilkS")
		)
		(fp_line
			(start 0.7874 0.4064)
			(end 0.7874 -0.4064)
			(stroke
				(width 0.1524)
				(type default)
			)
			(layer "B.SilkS")
		)
		(fp_line
			(start -0.7874 0.4064)
			(end 0.7874 0.4064)
			(stroke
				(width 0.1524)
				(type default)
			)
			(layer "B.SilkS")
		)
		(fp_line
			(start 0.67945 -0.305054)
			(end 0.12065 -0.305054)
			(stroke
				(width 0.1)
				(type default)
			)
			(layer "B.Fab")
		)
		(fp_line
			(start 0.12065 -0.305054)
			(end 0.12065 -0.2794)
			(stroke
				(width 0.1)
				(type default)
			)
			(layer "B.Fab")
		)
		(fp_line
			(start -0.12065 -0.3048)
			(end -0.67945 -0.3048)
			(stroke
				(width 0.1)
				(type default)
			)
			(layer "B.Fab")
		)
		(fp_line
			(start -0.67945 -0.3048)
			(end -0.67945 0.3048)
			(stroke
				(width 0.1)
				(type default)
			)
			(layer "B.Fab")
		)
		(fp_line
			(start 0.12065 -0.2794)
			(end -0.12065 -0.2794)
			(stroke
				(width 0.1)
				(type default)
			)
			(layer "B.Fab")
		)
		(fp_line
			(start -0.12065 -0.2794)
			(end -0.12065 -0.3048)
			(stroke
				(width 0.1)
				(type default)
			)
			(layer "B.Fab")
		)
		(fp_line
			(start 0.12065 0.2794)
			(end 0.12065 0.3048)
			(stroke
				(width 0.1)
				(type default)
			)
			(layer "B.Fab")
		)
		(fp_line
			(start -0.120396 0.2794)
			(end 0.12065 0.2794)
			(stroke
				(width 0.1)
				(type default)
			)
			(layer "B.Fab")
		)
		(fp_line
			(start 0.67945 0.3048)
			(end 0.67945 -0.305054)
			(stroke
				(width 0.1)
				(type default)
			)
			(layer "B.Fab")
		)
		(fp_line
			(start 0.12065 0.3048)
			(end 0.67945 0.3048)
			(stroke
				(width 0.1)
				(type default)
			)
			(layer "B.Fab")
		)
		(fp_line
			(start -0.120396 0.3048)
			(end -0.120396 0.2794)
			(stroke
				(width 0.1)
				(type default)
			)
			(layer "B.Fab")
		)
		(fp_line
			(start -0.67945 0.3048)
			(end -0.120396 0.3048)
			(stroke
				(width 0.1)
				(type default)
			)
			(layer "B.Fab")
		)
		(pad "1" smd circle
			(at 0.40005 0 270)
			(size 0 0)
			(layers "B.Cu" "B.Mask" "B.Paste")
			(net "P3V3")
		)
		(pad "2" smd circle
			(at -0.40005 0 270)
			(size 0 0)
			(layers "B.Cu" "B.Mask" "B.Paste")
			(net "PD_DB2000_SMB_SA0")
		)
	)
	(footprint ""
		(layer "B.Cu")
		(at 71.385684 -188.458856 90)
		(property "Reference" "R59"
			(at 0 0 90)
			(layer "B.SilkS")
			(hide yes)
			(effects
				(font
					(size 1.27 1.27)
				)
				(justify mirror)
			)
		)
		(property "Value" ""
			(at 0 0 90)
			(layer "B.Fab")
			(effects
				(font
					(size 1.27 1.27)
				)
				(justify mirror)
			)
		)
		(duplicate_pad_numbers_are_jumpers no)
		(fp_line
			(start 0.7874 -0.4064)
			(end -0.7874 -0.4064)
			(stroke
				(width 0.1524)
				(type default)
			)
			(layer "B.SilkS")
		)
		(fp_line
			(start -0.7874 -0.4064)
			(end -0.7874 0.4064)
			(stroke
				(width 0.1524)
				(type default)
			)
			(layer "B.SilkS")
		)
		(fp_line
			(start 0.7874 0.4064)
			(end 0.7874 -0.4064)
			(stroke
				(width 0.1524)
				(type default)
			)
			(layer "B.SilkS")
		)
		(fp_line
			(start -0.7874 0.4064)
			(end 0.7874 0.4064)
			(stroke
				(width 0.1524)
				(type default)
			)
			(layer "B.SilkS")
		)
		(fp_line
			(start 0.67945 -0.305054)
			(end 0.12065 -0.305054)
			(stroke
				(width 0.1)
				(type default)
			)
			(layer "B.Fab")
		)
		(fp_line
			(start 0.12065 -0.305054)
			(end 0.12065 -0.2794)
			(stroke
				(width 0.1)
				(type default)
			)
			(layer "B.Fab")
		)
		(fp_line
			(start -0.12065 -0.3048)
			(end -0.67945 -0.3048)
			(stroke
				(width 0.1)
				(type default)
			)
			(layer "B.Fab")
		)
		(fp_line
			(start -0.67945 -0.3048)
			(end -0.67945 0.3048)
			(stroke
				(width 0.1)
				(type default)
			)
			(layer "B.Fab")
		)
		(fp_line
			(start 0.12065 -0.2794)
			(end -0.12065 -0.2794)
			(stroke
				(width 0.1)
				(type default)
			)
			(layer "B.Fab")
		)
		(fp_line
			(start -0.12065 -0.2794)
			(end -0.12065 -0.3048)
			(stroke
				(width 0.1)
				(type default)
			)
			(layer "B.Fab")
		)
		(fp_line
			(start 0.12065 0.2794)
			(end 0.12065 0.3048)
			(stroke
				(width 0.1)
				(type default)
			)
			(layer "B.Fab")
		)
		(fp_line
			(start -0.120396 0.2794)
			(end 0.12065 0.2794)
			(stroke
				(width 0.1)
				(type default)
			)
			(layer "B.Fab")
		)
		(fp_line
			(start 0.67945 0.3048)
			(end 0.67945 -0.305054)
			(stroke
				(width 0.1)
				(type default)
			)
			(layer "B.Fab")
		)
		(fp_line
			(start 0.12065 0.3048)
			(end 0.67945 0.3048)
			(stroke
				(width 0.1)
				(type default)
			)
			(layer "B.Fab")
		)
		(fp_line
			(start -0.120396 0.3048)
			(end -0.120396 0.2794)
			(stroke
				(width 0.1)
				(type default)
			)
			(layer "B.Fab")
		)
		(fp_line
			(start -0.67945 0.3048)
			(end -0.120396 0.3048)
			(stroke
				(width 0.1)
				(type default)
			)
			(layer "B.Fab")
		)
		(pad "1" smd circle
			(at 0.40005 0 270)
			(size 0 0)
			(layers "B.Cu" "B.Mask" "B.Paste")
			(net "SVID_CLK1_CPU1")
		)
		(pad "2" smd circle
			(at -0.40005 0 270)
			(size 0 0)
			(layers "B.Cu" "B.Mask" "B.Paste")
			(net "SVID_CLK1_CPU1_R")
		)
	)
)
